# T6G (Grand Teton) — schematic netlist excerpt (pin names and nets, part order shuffled) for the footprints in the layout excerpt that follows; sources: Cadence DE-HDL packaged netlist, KiCad conversion of 04192023_DAF0TMB3IC0_F0TG_MB_C_brd_V02_OCP.brd

R6156  Q_RES  0 5% CHIP  pkg 0201LF  page 113 : A = P2E_MB_BMC_RX_DP<0> ; B = P2E_MB_BMC_RX_R1_DP<0>
R9009  Q_RES  4.7K 5% CHIP  pkg 0402LF  page 123 : A = P3V3_AUX ; B = PRSNT_CABLE_SWB_B2_ISO_N
R3506  Q_RES  4.7K 5% EMPTY  pkg 0402LF  page 130 : A = P3V3_AUX ; B = GPU_FPGA_RST_R_N

(kicad_pcb
	(version 20260206)
	(generator "pcbnew")
	(generator_version "10.0")
	(general
		(thickness 1.6)
		(legacy_teardrops no)
	)
	(paper "A4")
	(title_block
		(title "04192023_DAF0TMB3IC0_F0TG_MB_C_brd_V02_OCP.brd")
		(comment 1 "Grand Teton / footprints 1980-1982 of 8354")
	)
	(layers
		(0 "F.Cu" signal "TOP")
		(4 "In1.Cu" signal "GND")
		(6 "In2.Cu" signal "IN1")
		(8 "In3.Cu" signal "GND1")
		(10 "In4.Cu" signal "IN2")
		(12 "In5.Cu" signal "GND2")
		(14 "In6.Cu" signal "IN3")
		(16 "In7.Cu" signal "GND3")
		(18 "In8.Cu" signal "VCC")
		(20 "In9.Cu" signal "VCC1")
		(22 "In10.Cu" signal "GND4")
		(24 "In11.Cu" signal "IN4")
		(26 "In12.Cu" signal "GND5")
		(28 "In13.Cu" signal "IN5")
		(30 "In14.Cu" signal "GND6")
		(32 "In15.Cu" signal "IN6")
		(34 "In16.Cu" signal "GND7")
		(2 "B.Cu" signal "BOTTOM")
		(9 "F.Adhes" user "F.Adhesive")
		(11 "B.Adhes" user "B.Adhesive")
		(13 "F.Paste" user "Package Geometry/Pastemask Top")
		(15 "B.Paste" user "Package Geometry/Pastemask Bottom")
		(5 "F.SilkS" user "Ref Des/Silkscreen Top")
		(7 "B.SilkS" user "Ref Des/Silkscreen Bottom")
		(1 "F.Mask" user "Board Geometry/Soldermask Top")
		(3 "B.Mask" user "Board Geometry/Soldermask Bottom")
		(17 "Dwgs.User" user "User.Drawings")
		(19 "Cmts.User" user "User.Comments")
		(21 "Eco1.User" user "User.Eco1")
		(23 "Eco2.User" user "User.Eco2")
		(25 "Edge.Cuts" user "Board Geometry/Outline")
		(27 "Margin" user)
		(31 "F.CrtYd" user "Package Geometry/Place Bound Top")
		(29 "B.CrtYd" user "Package Geometry/Place Bound Bottom")
		(35 "F.Fab" user "Ref Des/Assembly Top")
		(33 "B.Fab" user "Ref Des/Assembly Bottom")
	)
	(footprint ""
		(layer "F.Cu")
		(at 44.069 -435.61)
		(property "Reference" "R3506"
			(at 0 0 0)
			(layer "F.SilkS")
			(hide yes)
			(effects
				(font
					(size 1.27 1.27)
				)
			)
		)
		(property "Value" ""
			(at 0 0 0)
			(layer "F.Fab")
			(effects
				(font
					(size 1.27 1.27)
				)
			)
		)
		(duplicate_pad_numbers_are_jumpers no)
		(fp_line
			(start -0.7874 -0.4064)
			(end 0.7874 -0.4064)
			(stroke
				(width 0.1524)
				(type default)
			)
			(layer "F.SilkS")
		)
		(fp_line
			(start -0.7874 0.4064)
			(end -0.7874 -0.4064)
			(stroke
				(width 0.1524)
				(type default)
			)
			(layer "F.SilkS")
		)
		(fp_line
			(start 0.7874 -0.4064)
			(end 0.7874 0.4064)
			(stroke
				(width 0.1524)
				(type default)
			)
			(layer "F.SilkS")
		)
		(fp_line
			(start 0.7874 0.4064)
			(end -0.7874 0.4064)
			(stroke
				(width 0.1524)
				(type default)
			)
			(layer "F.SilkS")
		)
		(fp_line
			(start -0.67945 -0.305054)
			(end -0.12065 -0.305054)
			(stroke
				(width 0.1)
				(type default)
			)
			(layer "F.Fab")
		)
		(fp_line
			(start -0.67945 0.3048)
			(end -0.67945 -0.305054)
			(stroke
				(width 0.1)
				(type default)
			)
			(layer "F.Fab")
		)
		(fp_line
			(start -0.12065 -0.305054)
			(end -0.12065 -0.2794)
			(stroke
				(width 0.1)
				(type default)
			)
			(layer "F.Fab")
		)
		(fp_line
			(start -0.12065 -0.2794)
			(end 0.12065 -0.2794)
			(stroke
				(width 0.1)
				(type default)
			)
			(layer "F.Fab")
		)
		(fp_line
			(start -0.12065 0.2794)
			(end -0.12065 0.3048)
			(stroke
				(width 0.1)
				(type default)
			)
			(layer "F.Fab")
		)
		(fp_line
			(start -0.12065 0.3048)
			(end -0.67945 0.3048)
			(stroke
				(width 0.1)
				(type default)
			)
			(layer "F.Fab")
		)
		(fp_line
			(start 0.120396 0.2794)
			(end -0.12065 0.2794)
			(stroke
				(width 0.1)
				(type default)
			)
			(layer "F.Fab")
		)
		(fp_line
			(start 0.120396 0.3048)
			(end 0.120396 0.2794)
			(stroke
				(width 0.1)
				(type default)
			)
			(layer "F.Fab")
		)
		(fp_line
			(start 0.12065 -0.3048)
			(end 0.67945 -0.3048)
			(stroke
				(width 0.1)
				(type default)
			)
			(layer "F.Fab")
		)
		(fp_line
			(start 0.12065 -0.2794)
			(end 0.12065 -0.3048)
			(stroke
				(width 0.1)
				(type default)
			)
			(layer "F.Fab")
		)
		(fp_line
			(start 0.67945 -0.3048)
			(end 0.67945 0.3048)
			(stroke
				(width 0.1)
				(type default)
			)
			(layer "F.Fab")
		)
		(fp_line
			(start 0.67945 0.3048)
			(end 0.120396 0.3048)
			(stroke
				(width 0.1)
				(type default)
			)
			(layer "F.Fab")
		)
		(pad "1" smd circle
			(at -0.40005 0)
			(size 0 0)
			(layers "F.Cu" "F.Mask" "F.Paste")
			(net "P3V3_AUX")
		)
		(pad "2" smd circle
			(at 0.40005 0)
			(size 0 0)
			(layers "F.Cu" "F.Mask" "F.Paste")
			(net "GPU_FPGA_RST_R_N")
		)
	)
	(footprint ""
		(layer "F.Cu")
		(at 172.540422 -416.484816)
		(property "Reference" "R9009"
			(at 0 0 0)
			(layer "F.SilkS")
			(hide yes)
			(effects
				(font
					(size 1.27 1.27)
				)
			)
		)
		(property "Value" ""
			(at 0 0 0)
			(layer "F.Fab")
			(effects
				(font
					(size 1.27 1.27)
				)
			)
		)
		(duplicate_pad_numbers_are_jumpers no)
		(fp_line
			(start -0.7874 -0.4064)
			(end 0.7874 -0.4064)
			(stroke
				(width 0.1524)
				(type default)
			)
			(layer "F.SilkS")
		)
		(fp_line
			(start -0.7874 0.4064)
			(end -0.7874 -0.4064)
			(stroke
				(width 0.1524)
				(type default)
			)
			(layer "F.SilkS")
		)
		(fp_line
			(start 0.7874 -0.4064)
			(end 0.7874 0.4064)
			(stroke
				(width 0.1524)
				(type default)
			)
			(layer "F.SilkS")
		)
		(fp_line
			(start 0.7874 0.4064)
			(end -0.7874 0.4064)
			(stroke
				(width 0.1524)
				(type default)
			)
			(layer "F.SilkS")
		)
		(fp_line
			(start -0.67945 -0.305054)
			(end -0.12065 -0.305054)
			(stroke
				(width 0.1)
				(type default)
			)
			(layer "F.Fab")
		)
		(fp_line
			(start -0.67945 0.3048)
			(end -0.67945 -0.305054)
			(stroke
				(width 0.1)
				(type default)
			)
			(layer "F.Fab")
		)
		(fp_line
			(start -0.12065 -0.305054)
			(end -0.12065 -0.2794)
			(stroke
				(width 0.1)
				(type default)
			)
			(layer "F.Fab")
		)
		(fp_line
			(start -0.12065 -0.2794)
			(end 0.12065 -0.2794)
			(stroke
				(width 0.1)
				(type default)
			)
			(layer "F.Fab")
		)
		(fp_line
			(start -0.12065 0.2794)
			(end -0.12065 0.3048)
			(stroke
				(width 0.1)
				(type default)
			)
			(layer "F.Fab")
		)
		(fp_line
			(start -0.12065 0.3048)
			(end -0.67945 0.3048)
			(stroke
				(width 0.1)
				(type default)
			)
			(layer "F.Fab")
		)
		(fp_line
			(start 0.120396 0.2794)
			(end -0.12065 0.2794)
			(stroke
				(width 0.1)
				(type default)
			)
			(layer "F.Fab")
		)
		(fp_line
			(start 0.120396 0.3048)
			(end 0.120396 0.2794)
			(stroke
				(width 0.1)
				(type default)
			)
			(layer "F.Fab")
		)
		(fp_line
			(start 0.12065 -0.3048)
			(end 0.67945 -0.3048)
			(stroke
				(width 0.1)
				(type default)
			)
			(layer "F.Fab")
		)
		(fp_line
			(start 0.12065 -0.2794)
			(end 0.12065 -0.3048)
			(stroke
				(width 0.1)
				(type default)
			)
			(layer "F.Fab")
		)
		(fp_line
			(start 0.67945 -0.3048)
			(end 0.67945 0.3048)
			(stroke
				(width 0.1)
				(type default)
			)
			(layer "F.Fab")
		)
		(fp_line
			(start 0.67945 0.3048)
			(end 0.120396 0.3048)
			(stroke
				(width 0.1)
				(type default)
			)
			(layer "F.Fab")
		)
		(pad "1" smd circle
			(at -0.40005 0)
			(size 0 0)
			(layers "F.Cu" "F.Mask" "F.Paste")
			(net "P3V3_AUX")
		)
		(pad "2" smd circle
			(at 0.40005 0)
			(size 0 0)
			(layers "F.Cu" "F.Mask" "F.Paste")
			(net "PRSNT_CABLE_SWB_B2_ISO_N")
		)
	)
	(footprint ""
		(layer "F.Cu")
		(at 28.021026 -428.755302)
		(property "Reference" "R6156"
			(at 0 0 0)
			(layer "F.SilkS")
			(hide yes)
			(effects
				(font
					(size 1.27 1.27)
				)
			)
		)
		(property "Value" ""
			(at 0 0 0)
			(layer "F.Fab")
			(effects
				(font
					(size 1.27 1.27)
				)
			)
		)
		(duplicate_pad_numbers_are_jumpers no)
		(fp_line
			(start -0.32512 -0.175006)
			(end 0.32512 -0.175006)
			(stroke
				(width 0.1)
				(type default)
			)
			(layer "F.Fab")
		)
		(fp_line
			(start -0.32512 0.175006)
			(end -0.32512 -0.175006)
			(stroke
				(width 0.1)
				(type default)
			)
			(layer "F.Fab")
		)
		(fp_line
			(start 0.32512 -0.175006)
			(end 0.32512 0.175006)
			(stroke
				(width 0.1)
				(type default)
			)
			(layer "F.Fab")
		)
		(fp_line
			(start 0.32512 0.175006)
			(end -0.32512 0.175006)
			(stroke
				(width 0.1)
				(type default)
			)
			(layer "F.Fab")
		)
		(pad "1" smd rect
			(at -0.2667 0)
			(size 0.3048 0.381)
			(layers "F.Cu" "F.Mask" "F.Paste")
			(net "P2E_MB_BMC_RX_DP<0>")
		)
		(pad "2" smd rect
			(at 0.2667 0 180)
			(size 0.3048 0.381)
			(layers "F.Cu" "F.Mask" "F.Paste")
			(net "P2E_MB_BMC_RX_R1_DP<0>")
		)
	)
)
